FILE_TYPE = MULTI_PHYS_TABLE;

PART 'PCA9545APW'

{========================================================================================}
:VALUE        | PART_TYPE | MATERIAL | PART_NUMBER    = STANDARD        | LIFECYCLE      | PART_NUMBER   | JEDEC_TYPE             | DESCRIPTION                   | MANUFTR | MANUF_PN     | RD_CMPLS_LVL | CMPLS_LVL | FROM_PJ    | CLASS | DIP_SMD | DATA                  | EE_CHECK_LIST | FP_ECN | PSL | CREATOR | STATUS | MSD | ESD_CDM | ESD_HBM | ESD_MM | PIN_LENGTH_SHORT_PIN | PIN_LENGTH_LONG_PIN | CREATEDAY  ;
{========================================================================================}
 'PCA9545APW' | 'SMLF'    | 'IC'     | 'AL009545K17'(!) = ''               | ''               | 'AL009545K17' |'TSSOP20_0-65_6-5X4-4'| 'IC (20P) PCA9545APW (TSSOP)' | 'PHI'   | 'PCA9545APW' | 'EP'         | 'EP(V1)'  | 'S8A-LUKE' | 'IC'  | ''      | 'PHI_ PCA9545APW.pdf' | ''            | ''     | ''  | ''      | ''     | ''  | ''      | ''      | ''     | '0 MILS'             | '0 MILS'            | '20210723'
 'PCA9545APW' | 'SMLF'    | 'EMPTY'  | 'AL009545K17'(!) = ''               | ''               | 'AL009545K17' |'TSSOP20_0-65_6-5X4-4'| 'IC (20P) PCA9545APW (TSSOP)' | 'PHI'   | 'PCA9545APW' | 'EP'         | 'EP(V1)'  | 'S8A-LUKE' | 'IC'  | ''      | 'PHI_ PCA9545APW.pdf' | ''            | ''     | ''  | ''      | ''     | ''  | ''      | ''      | ''     | '0 MILS'             | '0 MILS'            | '20210723'

END_PART

END.

